(kicad_pcb
	(version 20211014)
	(generator pcbnew)
	(general
    (thickness 1.6)
  )
	(paper "A4")
	(title_block
    (title "SA800U (Snapdragon 845) Baseboard")
    (date "2023-10-19")
    (rev "1.0.3")
    (company "Antmicro Ltd.")
    (comment 1 "www.antmicro.com")
		(comment 9 "footprints 435-445 of 589")
	)
	(layers
    (0 "F.Cu" signal)
    (1 "In1.Cu" power)
    (2 "In2.Cu" signal)
    (3 "In3.Cu" signal)
    (4 "In4.Cu" power)
    (31 "B.Cu" signal)
    (32 "B.Adhes" user "B.Adhesive")
    (33 "F.Adhes" user "F.Adhesive")
    (34 "B.Paste" user)
    (35 "F.Paste" user)
    (36 "B.SilkS" user "B.Silkscreen")
    (37 "F.SilkS" user "F.Silkscreen")
    (38 "B.Mask" user)
    (39 "F.Mask" user)
    (40 "Dwgs.User" user "User.Drawings")
    (41 "Cmts.User" user "User.Comments")
    (42 "Eco1.User" user "User.Eco1")
    (43 "Eco2.User" user "User.Eco2")
    (44 "Edge.Cuts" user)
    (45 "Margin" user)
    (46 "B.CrtYd" user "B.Courtyard")
    (47 "F.CrtYd" user "F.Courtyard")
    (48 "B.Fab" user)
    (49 "F.Fab" user)
  )
	(footprint "sa800u-baseboard-hw-footprints:D_SOD-323F" (layer "B.Cu")
    (tedit 60F16F6B)
    (at 137.17 148.425 180)
    (property "Author" "Antmicro")
    (property "License" "Apache-2.0")
    (property "MPN" "1N4148WS")
    (property "Manufacturer" "ON Semiconductor")
    (property "Sheetfile" "hdmi-converter.kicad_sch")
    (property "Sheetname" "HDMI converter")
    (attr smd)
    (fp_text reference "D1" (at -0.62 -1.725) (layer "B.SilkS")
      (effects (font (size 0.7 0.7) (thickness 0.15)) (justify left bottom mirror))
    )
    (fp_text value "1N4148WS" (at -1.7 -1.9) (layer "B.Fab")
      (effects (font (size 0.7 0.7) (thickness 0.15)) (justify left bottom mirror))
    )
    (fp_text user "License: Apache-2.0" (at -1.8 -5.8) (layer "B.Fab") hide
      (effects (font (size 0.7 0.7) (thickness 0.15)) (justify left bottom mirror))
    )
    (fp_text user "${REFERENCE}" (at -1.8 -3.2) (layer "B.Fab") hide
      (effects (font (size 0.7 0.7) (thickness 0.15)) (justify left bottom mirror))
    )
    (fp_text user "Author: Antmicro" (at -1.8 -4.46) (layer "B.Fab") hide
      (effects (font (size 0.7 0.7) (thickness 0.15)) (justify left bottom mirror))
    )
    (fp_line (start 0.623 0.75) (end 0.973 0.75) (layer "B.SilkS") (width 0.15))
    (fp_line (start -0.5 0.426) (end -0.5 -0.424) (layer "B.SilkS") (width 0.15))
    (fp_line (start -0.625 0.75) (end -0.975 0.75) (layer "B.SilkS") (width 0.15))
    (fp_line (start -0.975 -0.748) (end -0.975 -0.45) (layer "B.SilkS") (width 0.15))
    (fp_line (start -0.975 0.75) (end -0.975 0.45) (layer "B.SilkS") (width 0.15))
    (fp_line (start 0.973 0.75) (end 0.973 0.45) (layer "B.SilkS") (width 0.15))
    (fp_line (start 0.973 -0.45) (end 0.973 -0.748) (layer "B.SilkS") (width 0.15))
    (fp_line (start -0.625 -0.748) (end -0.975 -0.748) (layer "B.SilkS") (width 0.15))
    (fp_line (start 0.973 -0.748) (end 0.623 -0.748) (layer "B.SilkS") (width 0.15))
    (fp_rect (start -1.6 0.827) (end 1.599 -0.825) (layer "B.CrtYd") (width 0.05) (fill none))
    (fp_line (start 0.848 0.625) (end 0.848 -0.623) (layer "B.Fab") (width 0.15))
    (fp_line (start -0.85 0.625) (end 0.848 0.625) (layer "B.Fab") (width 0.15))
    (fp_line (start -0.85 -0.623) (end -0.85 0.625) (layer "B.Fab") (width 0.15))
    (fp_line (start -0.85 -0.623) (end 0.848 -0.623) (layer "B.Fab") (width 0.15))
    (pad "A" smd roundrect (at 1.05 0 180) (size 0.8 0.6) (layers "B.Cu" "B.Paste" "B.Mask") (roundrect_rratio 0.15)
      (net 131 "3V3_SYS") (pinfunction "A") (pintype "passive"))
    (pad "K" smd roundrect (at -1.051 0 180) (size 0.8 0.6) (layers "B.Cu" "B.Paste" "B.Mask") (roundrect_rratio 0.15)
      (net 366 "Net-(D1-PadK)") (pinfunction "K") (pintype "passive"))
  )
	(footprint "sa800u-baseboard-hw-footprints:R_0402_1005Metric" (layer "B.Cu")
    (tedit 5FD9C158)
    (at 139.25 147.5 90)
    (descr "Resistor SMD 0402")
    (tags "resistor SMD 0402")
    (property "Author" "Antmicro")
    (property "License" "Apache-2.0")
    (property "MPN" "CR0402-FX-2702GLF")
    (property "Manufacturer" "Bourns")
    (property "Sheetfile" "hdmi-converter.kicad_sch")
    (property "Sheetname" "HDMI converter")
    (property "Tolerance" "1%")
    (property "Val" "27k")
    (attr smd)
    (fp_text reference "R33" (at -0.8 0.45 270) (layer "B.SilkS")
      (effects (font (size 0.7 0.7) (thickness 0.15)) (justify left bottom mirror))
    )
    (fp_text value "R_27k_0402" (at 0 -1.4 270) (layer "B.Fab")
      (effects (font (size 0.7 0.7) (thickness 0.15)) (justify left bottom mirror))
    )
    (fp_text user "License: Apache-2.0" (at -0.95 -5.169 270) (layer "B.Fab") hide
      (effects (font (size 0.7 0.7) (thickness 0.15)) (justify left bottom mirror))
    )
    (fp_text user "Author: Antmicro" (at -0.95 -4.169 270) (layer "B.Fab") hide
      (effects (font (size 0.7 0.7) (thickness 0.15)) (justify left bottom mirror))
    )
    (fp_text user "${REFERENCE}" (at -0.95 -3.168 270) (layer "B.Fab") hide
      (effects (font (size 0.7 0.7) (thickness 0.15)) (justify left bottom mirror))
    )
    (fp_rect (start -0.93 0.47) (end 0.93 -0.47) (layer "B.CrtYd") (width 0.05) (fill none))
    (fp_rect (start -0.5 0.25) (end 0.5 -0.25) (layer "B.Fab") (width 0.15) (fill none))
    (pad "1" smd roundrect (at -0.485 0 90) (size 0.59 0.64) (layers "B.Cu" "B.Paste" "B.Mask") (roundrect_rratio 0.25)
      (net 366 "Net-(D1-PadK)") (pintype "passive"))
    (pad "2" smd roundrect (at 0.485 0 90) (size 0.59 0.64) (layers "B.Cu" "B.Paste" "B.Mask") (roundrect_rratio 0.25)
      (net 233 "/HDMI converter/HDMI_CEC") (pintype "passive"))
  )
	(footprint "sa800u-baseboard-hw-footprints:R_0402_1005Metric" (layer "B.Cu")
    (tedit 5FD9C158)
    (at 139.25 145.55 90)
    (descr "Resistor SMD 0402")
    (tags "resistor SMD 0402")
    (property "Author" "Antmicro")
    (property "Current" "1A")
    (property "DNP" "DNP")
    (property "License" "Apache-2.0")
    (property "MPN" "ERJ2GE0R00X")
    (property "Manufacturer" "Panasonic")
    (property "Sheetfile" "hdmi-converter.kicad_sch")
    (property "Sheetname" "HDMI converter")
    (property "Tolerance" "")
    (property "Val" "0R")
    (attr exclude_from_pos_files)
    (fp_text reference "R31" (at 3.01 0.44 270) (layer "B.SilkS")
      (effects (font (size 0.7 0.7) (thickness 0.15)) (justify left bottom mirror))
    )
    (fp_text value "R_0R_0402" (at 0 -1.4 270) (layer "B.Fab")
      (effects (font (size 0.7 0.7) (thickness 0.15)) (justify left bottom mirror))
    )
    (fp_text user "License: Apache-2.0" (at -0.95 -5.169 270) (layer "B.Fab") hide
      (effects (font (size 0.7 0.7) (thickness 0.15)) (justify left bottom mirror))
    )
    (fp_text user "Author: Antmicro" (at -0.95 -4.169 270) (layer "B.Fab") hide
      (effects (font (size 0.7 0.7) (thickness 0.15)) (justify left bottom mirror))
    )
    (fp_text user "${REFERENCE}" (at -0.95 -3.168 270) (layer "B.Fab") hide
      (effects (font (size 0.7 0.7) (thickness 0.15)) (justify left bottom mirror))
    )
    (fp_rect (start -0.93 0.47) (end 0.93 -0.47) (layer "B.CrtYd") (width 0.05) (fill none))
    (fp_rect (start -0.5 0.25) (end 0.5 -0.25) (layer "B.Fab") (width 0.15) (fill none))
    (pad "1" smd roundrect (at -0.485 0 90) (size 0.59 0.64) (layers "B.Cu" "B.Paste" "B.Mask") (roundrect_rratio 0.25)
      (net 233 "/HDMI converter/HDMI_CEC") (pintype "passive"))
    (pad "2" smd roundrect (at 0.485 0 90) (size 0.59 0.64) (layers "B.Cu" "B.Paste" "B.Mask") (roundrect_rratio 0.25)
      (net 285 "/HDMI converter/LT9611_CEC") (pintype "passive"))
  )
	(footprint "sa800u-baseboard-hw-footprints:R_0402_1005Metric" (layer "B.Cu")
    (tedit 5FD9C158)
    (at 135.65 145.55 90)
    (descr "Resistor SMD 0402")
    (tags "resistor SMD 0402")
    (property "Author" "Antmicro")
    (property "License" "Apache-2.0")
    (property "MPN" "CR0402-FX-1002GLF")
    (property "Manufacturer" "Bourns")
    (property "Sheetfile" "hdmi-converter.kicad_sch")
    (property "Sheetname" "HDMI converter")
    (property "Tolerance" "1%")
    (property "Val" "10k")
    (attr smd)
    (fp_text reference "R29" (at 3.05 0.41 270) (layer "B.SilkS")
      (effects (font (size 0.7 0.7) (thickness 0.15)) (justify left bottom mirror))
    )
    (fp_text value "R_10k_0402" (at 0 -1.4 270) (layer "B.Fab")
      (effects (font (size 0.7 0.7) (thickness 0.15)) (justify left bottom mirror))
    )
    (fp_text user "Author: Antmicro" (at -0.95 -4.169 270) (layer "B.Fab") hide
      (effects (font (size 0.7 0.7) (thickness 0.15)) (justify left bottom mirror))
    )
    (fp_text user "${REFERENCE}" (at -0.95 -3.168 270) (layer "B.Fab") hide
      (effects (font (size 0.7 0.7) (thickness 0.15)) (justify left bottom mirror))
    )
    (fp_text user "License: Apache-2.0" (at -0.95 -5.169 270) (layer "B.Fab") hide
      (effects (font (size 0.7 0.7) (thickness 0.15)) (justify left bottom mirror))
    )
    (fp_rect (start -0.93 0.47) (end 0.93 -0.47) (layer "B.CrtYd") (width 0.05) (fill none))
    (fp_rect (start -0.5 0.25) (end 0.5 -0.25) (layer "B.Fab") (width 0.15) (fill none))
    (pad "1" smd roundrect (at -0.485 0 90) (size 0.59 0.64) (layers "B.Cu" "B.Paste" "B.Mask") (roundrect_rratio 0.25)
      (net 131 "3V3_SYS") (pintype "passive"))
    (pad "2" smd roundrect (at 0.485 0 90) (size 0.59 0.64) (layers "B.Cu" "B.Paste" "B.Mask") (roundrect_rratio 0.25)
      (net 154 "Net-(Q3-Pad1)") (pintype "passive"))
  )
	(footprint "sa800u-baseboard-hw-footprints:SC70-3" (layer "B.Cu")
    (tedit 615FF353)
    (at 137.45 146.05 -90)
    (property "Author" "Antmicro")
    (property "License" "Apache-2.0")
    (property "MPN" "BSS138PW")
    (property "Manufacturer" "Nexperia")
    (property "Sheetfile" "hdmi-converter.kicad_sch")
    (property "Sheetname" "HDMI converter")
    (attr smd)
    (fp_text reference "Q3" (at -1.56 -0.84 180) (layer "B.SilkS")
      (effects (font (size 0.7 0.7) (thickness 0.15)) (justify left bottom mirror))
    )
    (fp_text value "BSS138PW" (at 0 -2.3 90) (layer "B.Fab")
      (effects (font (size 0.7 0.7) (thickness 0.15)) (justify left bottom mirror))
    )
    (fp_text user "Author: Antmicro" (at -1.45 -5.782 90) (layer "B.Fab") hide
      (effects (font (size 0.7 0.7) (thickness 0.15)) (justify left bottom mirror))
    )
    (fp_text user "License: Apache-2.0" (at -1.45 -6.782 90) (layer "B.Fab") hide
      (effects (font (size 0.7 0.7) (thickness 0.15)) (justify left bottom mirror))
    )
    (fp_text user "${REFERENCE}" (at -1.45 -4.783 90) (layer "B.Fab") hide
      (effects (font (size 0.7 0.7) (thickness 0.15)) (justify left bottom mirror))
    )
    (fp_line (start 0.627 -0.6) (end 0.627 -1.001) (layer "B.SilkS") (width 0.15))
    (fp_line (start 0.627 0.6) (end 0.627 0.999) (layer "B.SilkS") (width 0.15))
    (fp_line (start -0.3 1) (end 0.627 0.999) (layer "B.SilkS") (width 0.15))
    (fp_line (start -0.3 -1) (end 0.627 -1.001) (layer "B.SilkS") (width 0.15))
    (fp_line (start 0.9 -0.4) (end 0.9 -1.3) (layer "B.CrtYd") (width 0.05))
    (fp_line (start 0.9 -1.3) (end -0.9 -1.3) (layer "B.CrtYd") (width 0.05))
    (fp_line (start -0.9 1) (end -1.4 1) (layer "B.CrtYd") (width 0.05))
    (fp_line (start -0.9 -1) (end -1.4 -1) (layer "B.CrtYd") (width 0.05))
    (fp_line (start 0.9 1.3) (end 0.9 0.4) (layer "B.CrtYd") (width 0.05))
    (fp_line (start -0.9 1.3) (end -0.9 1) (layer "B.CrtYd") (width 0.05))
    (fp_line (start -0.9 1.3) (end 0.9 1.3) (layer "B.CrtYd") (width 0.05))
    (fp_line (start 1.4 0.4) (end 1.4 -0.4) (layer "B.CrtYd") (width 0.05))
    (fp_line (start 0.9 0.4) (end 1.4 0.4) (layer "B.CrtYd") (width 0.05))
    (fp_line (start -1.4 -1) (end -1.4 1) (layer "B.CrtYd") (width 0.05))
    (fp_line (start -0.9 -1.3) (end -0.9 -1) (layer "B.CrtYd") (width 0.05))
    (fp_line (start 1.4 -0.4) (end 0.9 -0.4) (layer "B.CrtYd") (width 0.05))
    (fp_rect (start -0.623 0.999) (end 0.627 -1.001) (layer "B.Fab") (width 0.15) (fill none))
    (pad "1" smd rect (at -1.051 0.65 180) (size 0.6 0.6) (layers "B.Cu" "B.Paste" "B.Mask")
      (net 154 "Net-(Q3-Pad1)") (pinfunction "G") (pintype "bidirectional"))
    (pad "2" smd rect (at -1.051 -0.65 180) (size 0.6 0.6) (layers "B.Cu" "B.Paste" "B.Mask")
      (net 285 "/HDMI converter/LT9611_CEC") (pinfunction "S") (pintype "bidirectional"))
    (pad "3" smd rect (at 1.05 0 180) (size 0.6 0.6) (layers "B.Cu" "B.Paste" "B.Mask")
      (net 233 "/HDMI converter/HDMI_CEC") (pinfunction "D") (pintype "bidirectional"))
  )
	(footprint "sa800u-baseboard-hw-footprints:TP_SMD_0.75mm" (layer "B.Cu")
    (tedit 5E4A9375)
    (at 124.4 130.5)
    (property "Author" "Antmicro")
    (property "License" "Apache-2.0")
    (property "MPN" "")
    (property "Manufacturer" "")
    (property "Sheetfile" "usb-c-interface.kicad_sch")
    (property "Sheetname" "USB-C Interface ")
    (attr smd)
    (fp_text reference "TP99" (at -0.31 0.4 180) (layer "B.SilkS")
      (effects (font (size 0.7 0.7) (thickness 0.15)) (justify left bottom mirror))
    )
    (fp_text value "TP_0.75mm_SMD" (at 0 -1.2 180) (layer "B.Fab")
      (effects (font (size 0.7 0.7) (thickness 0.15)) (justify left bottom mirror))
    )
    (fp_text user "License: Apache-2.0" (at -0.4 -5.101 180) (layer "B.Fab") hide
      (effects (font (size 0.7 0.7) (thickness 0.15)) (justify left bottom mirror))
    )
    (fp_text user "${REFERENCE}" (at -0.4 -2.7 180) (layer "B.Fab") hide
      (effects (font (size 0.7 0.7) (thickness 0.15)) (justify left bottom mirror))
    )
    (fp_text user "Author: Antmicro" (at -0.4 -3.901 180) (layer "B.Fab") hide
      (effects (font (size 0.7 0.7) (thickness 0.15)) (justify left bottom mirror))
    )
    (pad "1" smd circle (at 0 0) (size 0.75 0.75) (layers "B.Cu" "B.Mask")
      (net 130 "DBG_TXD") (pinfunction "1") (pintype "passive"))
  )
	(footprint "sa800u-baseboard-hw-footprints:TP_SMD_0.75mm" (layer "B.Cu")
    (tedit 5E4A9375)
    (at 126.4 132.8 180)
    (property "Author" "Antmicro")
    (property "License" "Apache-2.0")
    (property "MPN" "")
    (property "Manufacturer" "")
    (property "Sheetfile" "usb-c-interface.kicad_sch")
    (property "Sheetname" "USB-C Interface ")
    (attr smd)
    (fp_text reference "TP101" (at -3.75 -0.35) (layer "B.SilkS")
      (effects (font (size 0.7 0.7) (thickness 0.15)) (justify left bottom mirror))
    )
    (fp_text value "TP_0.75mm_SMD" (at 0 -1.2) (layer "B.Fab")
      (effects (font (size 0.7 0.7) (thickness 0.15)) (justify left bottom mirror))
    )
    (fp_text user "License: Apache-2.0" (at -0.4 -5.101) (layer "B.Fab") hide
      (effects (font (size 0.7 0.7) (thickness 0.15)) (justify left bottom mirror))
    )
    (fp_text user "${REFERENCE}" (at -0.4 -2.7) (layer "B.Fab") hide
      (effects (font (size 0.7 0.7) (thickness 0.15)) (justify left bottom mirror))
    )
    (fp_text user "Author: Antmicro" (at -0.4 -3.901) (layer "B.Fab") hide
      (effects (font (size 0.7 0.7) (thickness 0.15)) (justify left bottom mirror))
    )
    (pad "1" smd circle (at 0 0 180) (size 0.75 0.75) (layers "B.Cu" "B.Mask")
      (net 127 "1V8_DBG") (pinfunction "1") (pintype "passive"))
  )
	(footprint "sa800u-baseboard-hw-footprints:TP_SMD_0.75mm" (layer "B.Cu")
    (tedit 5E4A9375)
    (at 108.8 147.6 90)
    (property "Author" "Antmicro")
    (property "License" "Apache-2.0")
    (property "MPN" "")
    (property "Manufacturer" "")
    (property "Sheetfile" "usb-c-interface.kicad_sch")
    (property "Sheetname" "USB-C Interface ")
    (attr smd)
    (fp_text reference "TP102" (at -0.33 -0.03 270) (layer "B.SilkS")
      (effects (font (size 0.7 0.7) (thickness 0.15)) (justify left bottom mirror))
    )
    (fp_text value "TP_0.75mm_SMD" (at 0 -1.2 270) (layer "B.Fab")
      (effects (font (size 0.7 0.7) (thickness 0.15)) (justify left bottom mirror))
    )
    (fp_text user "${REFERENCE}" (at -0.4 -2.7 270) (layer "B.Fab") hide
      (effects (font (size 0.7 0.7) (thickness 0.15)) (justify left bottom mirror))
    )
    (fp_text user "Author: Antmicro" (at -0.4 -3.901 270) (layer "B.Fab") hide
      (effects (font (size 0.7 0.7) (thickness 0.15)) (justify left bottom mirror))
    )
    (fp_text user "License: Apache-2.0" (at -0.4 -5.101 270) (layer "B.Fab") hide
      (effects (font (size 0.7 0.7) (thickness 0.15)) (justify left bottom mirror))
    )
    (pad "1" smd circle (at 0 0 90) (size 0.75 0.75) (layers "B.Cu" "B.Mask")
      (net 301 "/USB-C Interface /USB2_EN_5V") (pinfunction "1") (pintype "passive"))
  )
	(footprint "sa800u-baseboard-hw-footprints:TP_SMD_0.75mm" (layer "B.Cu")
    (tedit 5E4A9375)
    (at 93.6 144.6)
    (property "Author" "Antmicro")
    (property "License" "Apache-2.0")
    (property "MPN" "")
    (property "Manufacturer" "")
    (property "Sheetfile" "usb-c-interface.kicad_sch")
    (property "Sheetname" "USB-C Interface ")
    (attr smd)
    (fp_text reference "TP103" (at 0.63 -3.72 90) (layer "B.SilkS")
      (effects (font (size 0.7 0.7) (thickness 0.15)) (justify left bottom mirror))
    )
    (fp_text value "TP_0.75mm_SMD" (at 0 -1.2 180) (layer "B.Fab")
      (effects (font (size 0.7 0.7) (thickness 0.15)) (justify left bottom mirror))
    )
    (fp_text user "${REFERENCE}" (at -0.4 -2.7 180) (layer "B.Fab") hide
      (effects (font (size 0.7 0.7) (thickness 0.15)) (justify left bottom mirror))
    )
    (fp_text user "Author: Antmicro" (at -0.4 -3.901 180) (layer "B.Fab") hide
      (effects (font (size 0.7 0.7) (thickness 0.15)) (justify left bottom mirror))
    )
    (fp_text user "License: Apache-2.0" (at -0.4 -5.101 180) (layer "B.Fab") hide
      (effects (font (size 0.7 0.7) (thickness 0.15)) (justify left bottom mirror))
    )
    (pad "1" smd circle (at 0 0) (size 0.75 0.75) (layers "B.Cu" "B.Mask")
      (net 93 "SBU_SW_OE") (pinfunction "1") (pintype "passive"))
  )
	(footprint "sa800u-baseboard-hw-footprints:TP_SMD_0.75mm" (layer "B.Cu")
    (tedit 5E4A9375)
    (at 96.4 144.6)
    (property "Author" "Antmicro")
    (property "License" "Apache-2.0")
    (property "MPN" "")
    (property "Manufacturer" "")
    (property "Sheetfile" "usb-c-interface.kicad_sch")
    (property "Sheetname" "USB-C Interface ")
    (attr smd)
    (fp_text reference "TP104" (at 0.85 -3.67 270) (layer "B.SilkS")
      (effects (font (size 0.7 0.7) (thickness 0.15)) (justify left bottom mirror))
    )
    (fp_text value "TP_0.75mm_SMD" (at 0 -1.2 180) (layer "B.Fab")
      (effects (font (size 0.7 0.7) (thickness 0.15)) (justify left bottom mirror))
    )
    (fp_text user "License: Apache-2.0" (at -0.4 -5.101 180) (layer "B.Fab") hide
      (effects (font (size 0.7 0.7) (thickness 0.15)) (justify left bottom mirror))
    )
    (fp_text user "${REFERENCE}" (at -0.4 -2.7 180) (layer "B.Fab") hide
      (effects (font (size 0.7 0.7) (thickness 0.15)) (justify left bottom mirror))
    )
    (fp_text user "Author: Antmicro" (at -0.4 -3.901 180) (layer "B.Fab") hide
      (effects (font (size 0.7 0.7) (thickness 0.15)) (justify left bottom mirror))
    )
    (pad "1" smd circle (at 0 0) (size 0.75 0.75) (layers "B.Cu" "B.Mask")
      (net 98 "SBU_SW_SEL") (pinfunction "1") (pintype "passive"))
  )
	(footprint "sa800u-baseboard-hw-footprints:TP_SMD_0.75mm" (layer "B.Cu")
    (tedit 5E4A9375)
    (at 108.3 135.9 -90)
    (property "Author" "Antmicro")
    (property "License" "Apache-2.0")
    (property "MPN" "")
    (property "Manufacturer" "")
    (property "Sheetfile" "usb-c-interface.kicad_sch")
    (property "Sheetname" "USB-C Interface ")
    (attr smd)
    (fp_text reference "TP105" (at -3.71 -0.37 90) (layer "B.SilkS")
      (effects (font (size 0.7 0.7) (thickness 0.15)) (justify left bottom mirror))
    )
    (fp_text value "TP_0.75mm_SMD" (at 0 -1.2 90) (layer "B.Fab")
      (effects (font (size 0.7 0.7) (thickness 0.15)) (justify left bottom mirror))
    )
    (fp_text user "Author: Antmicro" (at -0.4 -3.901 90) (layer "B.Fab") hide
      (effects (font (size 0.7 0.7) (thickness 0.15)) (justify left bottom mirror))
    )
    (fp_text user "License: Apache-2.0" (at -0.4 -5.101 90) (layer "B.Fab") hide
      (effects (font (size 0.7 0.7) (thickness 0.15)) (justify left bottom mirror))
    )
    (fp_text user "${REFERENCE}" (at -0.4 -2.7 90) (layer "B.Fab") hide
      (effects (font (size 0.7 0.7) (thickness 0.15)) (justify left bottom mirror))
    )
    (pad "1" smd circle (at 0 0 270) (size 0.75 0.75) (layers "B.Cu" "B.Mask")
      (net 99 "USB2_SINK") (pinfunction "1") (pintype "passive"))
  )
)
